FILE_TYPE = CONNECTIVITY;
{Allegro Design Entry HDL 17.2-2016 S081 (4005846) 1/11/2022}
"PAGE_NUMBER" = 266;
0"NC";
END.
